# S9S_MB_2U (Grand Teton) — schematic netlist excerpt (pin names and nets, part order shuffled) for the footprints in the layout excerpt that follows; sources: Cadence DE-HDL packaged netlist, KiCad conversion of 03242023_DA0F0TMBIJ0_F0T_Motherboard_J_brd_V01_OCP.brd

R1411  Q_RES  2K 1% CHIP  pkg 0402LF  page 219 : A = FM_PVCCFA_EHV_FIVRA_CPU0_R_EN ; B = GND
PC2153  Q_CAP  0.22UF 16V 10% X7R  pkg 0402  page 157 : A = P12V_OCP_TIMER_1 ; B = GND

(kicad_pcb
	(version 20260206)
	(generator "pcbnew")
	(generator_version "10.0")
	(general
		(thickness 1.6)
		(legacy_teardrops no)
	)
	(paper "A4")
	(title_block
		(title "03242023_DA0F0TMBIJ0_F0T_Motherboard_J_brd_V01_OCP.brd")
		(comment 1 "Grand Teton / footprints 2827-2828 of 6105")
	)
	(layers
		(0 "F.Cu" signal "TOP")
		(4 "In1.Cu" signal "GND")
		(6 "In2.Cu" signal "IN1")
		(8 "In3.Cu" signal "GND1")
		(10 "In4.Cu" signal "IN2")
		(12 "In5.Cu" signal "GND2")
		(14 "In6.Cu" signal "IN3")
		(16 "In7.Cu" signal "GND3")
		(18 "In8.Cu" signal "VCC")
		(20 "In9.Cu" signal "VCC1")
		(22 "In10.Cu" signal "GND4")
		(24 "In11.Cu" signal "IN4")
		(26 "In12.Cu" signal "GND5")
		(28 "In13.Cu" signal "IN5")
		(30 "In14.Cu" signal "GND6")
		(32 "In15.Cu" signal "IN6")
		(34 "In16.Cu" signal "GND7")
		(2 "B.Cu" signal "BOTTOM")
		(9 "F.Adhes" user "F.Adhesive")
		(11 "B.Adhes" user "B.Adhesive")
		(13 "F.Paste" user "Package Geometry/Pastemask Top")
		(15 "B.Paste" user "Package Geometry/Pastemask Bottom")
		(5 "F.SilkS" user "Ref Des/Silkscreen Top")
		(7 "B.SilkS" user "Ref Des/Silkscreen Bottom")
		(1 "F.Mask" user "Board Geometry/Soldermask Top")
		(3 "B.Mask" user "Board Geometry/Soldermask Bottom")
		(17 "Dwgs.User" user "User.Drawings")
		(19 "Cmts.User" user "User.Comments")
		(21 "Eco1.User" user "User.Eco1")
		(23 "Eco2.User" user "User.Eco2")
		(25 "Edge.Cuts" user "Board Geometry/Outline")
		(27 "Margin" user)
		(31 "F.CrtYd" user "Package Geometry/Place Bound Top")
		(29 "B.CrtYd" user "Package Geometry/Place Bound Bottom")
		(35 "F.Fab" user "Ref Des/Assembly Top")
		(33 "B.Fab" user "Ref Des/Assembly Bottom")
	)
	(footprint ""
		(layer "F.Cu")
		(at 171.50588 -126.964948 90)
		(property "Reference" "R1411"
			(at 0 0 90)
			(layer "F.SilkS")
			(hide yes)
			(effects
				(font
					(size 1.27 1.27)
				)
			)
		)
		(property "Value" ""
			(at 0 0 90)
			(layer "F.Fab")
			(effects
				(font
					(size 1.27 1.27)
				)
			)
		)
		(duplicate_pad_numbers_are_jumpers no)
		(fp_line
			(start 0.7874 -0.4064)
			(end 0.7874 0.4064)
			(stroke
				(width 0.1524)
				(type default)
			)
			(layer "F.SilkS")
		)
		(fp_line
			(start -0.7874 -0.4064)
			(end 0.7874 -0.4064)
			(stroke
				(width 0.1524)
				(type default)
			)
			(layer "F.SilkS")
		)
		(fp_line
			(start 0.7874 0.4064)
			(end -0.7874 0.4064)
			(stroke
				(width 0.1524)
				(type default)
			)
			(layer "F.SilkS")
		)
		(fp_line
			(start -0.7874 0.4064)
			(end -0.7874 -0.4064)
			(stroke
				(width 0.1524)
				(type default)
			)
			(layer "F.SilkS")
		)
		(fp_line
			(start -0.12065 -0.305054)
			(end -0.12065 -0.2794)
			(stroke
				(width 0.1)
				(type default)
			)
			(layer "F.Fab")
		)
		(fp_line
			(start -0.67945 -0.305054)
			(end -0.12065 -0.305054)
			(stroke
				(width 0.1)
				(type default)
			)
			(layer "F.Fab")
		)
		(fp_line
			(start 0.67945 -0.3048)
			(end 0.67945 0.3048)
			(stroke
				(width 0.1)
				(type default)
			)
			(layer "F.Fab")
		)
		(fp_line
			(start 0.12065 -0.3048)
			(end 0.67945 -0.3048)
			(stroke
				(width 0.1)
				(type default)
			)
			(layer "F.Fab")
		)
		(fp_line
			(start 0.12065 -0.2794)
			(end 0.12065 -0.3048)
			(stroke
				(width 0.1)
				(type default)
			)
			(layer "F.Fab")
		)
		(fp_line
			(start -0.12065 -0.2794)
			(end 0.12065 -0.2794)
			(stroke
				(width 0.1)
				(type default)
			)
			(layer "F.Fab")
		)
		(fp_line
			(start 0.120396 0.2794)
			(end -0.12065 0.2794)
			(stroke
				(width 0.1)
				(type default)
			)
			(layer "F.Fab")
		)
		(fp_line
			(start -0.12065 0.2794)
			(end -0.12065 0.3048)
			(stroke
				(width 0.1)
				(type default)
			)
			(layer "F.Fab")
		)
		(fp_line
			(start 0.67945 0.3048)
			(end 0.120396 0.3048)
			(stroke
				(width 0.1)
				(type default)
			)
			(layer "F.Fab")
		)
		(fp_line
			(start 0.120396 0.3048)
			(end 0.120396 0.2794)
			(stroke
				(width 0.1)
				(type default)
			)
			(layer "F.Fab")
		)
		(fp_line
			(start -0.12065 0.3048)
			(end -0.67945 0.3048)
			(stroke
				(width 0.1)
				(type default)
			)
			(layer "F.Fab")
		)
		(fp_line
			(start -0.67945 0.3048)
			(end -0.67945 -0.305054)
			(stroke
				(width 0.1)
				(type default)
			)
			(layer "F.Fab")
		)
		(pad "1" smd circle
			(at -0.40005 0 90)
			(size 0 0)
			(layers "F.Cu" "F.Mask" "F.Paste")
			(net "FM_PVCCFA_EHV_FIVRA_CPU0_R_EN")
		)
		(pad "2" smd circle
			(at 0.40005 0 90)
			(size 0 0)
			(layers "F.Cu" "F.Mask" "F.Paste")
			(net "GND")
		)
	)
	(footprint ""
		(layer "F.Cu")
		(at 443.717172 -32.173418 90)
		(property "Reference" "PC2153"
			(at 0 0 90)
			(layer "F.SilkS")
			(hide yes)
			(effects
				(font
					(size 1.27 1.27)
				)
			)
		)
		(property "Value" ""
			(at 0 0 90)
			(layer "F.Fab")
			(effects
				(font
					(size 1.27 1.27)
				)
			)
		)
		(duplicate_pad_numbers_are_jumpers no)
		(fp_line
			(start 0.7874 -0.4064)
			(end 0.7874 0.4064)
			(stroke
				(width 0.1524)
				(type default)
			)
			(layer "F.SilkS")
		)
		(fp_line
			(start -0.7874 -0.4064)
			(end 0.7874 -0.4064)
			(stroke
				(width 0.1524)
				(type default)
			)
			(layer "F.SilkS")
		)
		(fp_line
			(start 0.7874 0.4064)
			(end -0.7874 0.4064)
			(stroke
				(width 0.1524)
				(type default)
			)
			(layer "F.SilkS")
		)
		(fp_line
			(start -0.7874 0.4064)
			(end -0.7874 -0.4064)
			(stroke
				(width 0.1524)
				(type default)
			)
			(layer "F.SilkS")
		)
		(fp_line
			(start -0.12065 -0.305054)
			(end -0.12065 -0.2794)
			(stroke
				(width 0.1)
				(type default)
			)
			(layer "F.Fab")
		)
		(fp_line
			(start -0.67945 -0.305054)
			(end -0.12065 -0.305054)
			(stroke
				(width 0.1)
				(type default)
			)
			(layer "F.Fab")
		)
		(fp_line
			(start 0.67945 -0.3048)
			(end 0.67945 0.3048)
			(stroke
				(width 0.1)
				(type default)
			)
			(layer "F.Fab")
		)
		(fp_line
			(start 0.12065 -0.3048)
			(end 0.67945 -0.3048)
			(stroke
				(width 0.1)
				(type default)
			)
			(layer "F.Fab")
		)
		(fp_line
			(start 0.12065 -0.2794)
			(end 0.12065 -0.3048)
			(stroke
				(width 0.1)
				(type default)
			)
			(layer "F.Fab")
		)
		(fp_line
			(start -0.12065 -0.2794)
			(end 0.12065 -0.2794)
			(stroke
				(width 0.1)
				(type default)
			)
			(layer "F.Fab")
		)
		(fp_line
			(start 0.120396 0.2794)
			(end -0.12065 0.2794)
			(stroke
				(width 0.1)
				(type default)
			)
			(layer "F.Fab")
		)
		(fp_line
			(start -0.12065 0.2794)
			(end -0.12065 0.3048)
			(stroke
				(width 0.1)
				(type default)
			)
			(layer "F.Fab")
		)
		(fp_line
			(start 0.67945 0.3048)
			(end 0.120396 0.3048)
			(stroke
				(width 0.1)
				(type default)
			)
			(layer "F.Fab")
		)
		(fp_line
			(start 0.120396 0.3048)
			(end 0.120396 0.2794)
			(stroke
				(width 0.1)
				(type default)
			)
			(layer "F.Fab")
		)
		(fp_line
			(start -0.12065 0.3048)
			(end -0.67945 0.3048)
			(stroke
				(width 0.1)
				(type default)
			)
			(layer "F.Fab")
		)
		(fp_line
			(start -0.67945 0.3048)
			(end -0.67945 -0.305054)
			(stroke
				(width 0.1)
				(type default)
			)
			(layer "F.Fab")
		)
		(pad "1" smd circle
			(at -0.40005 0 90)
			(size 0 0)
			(layers "F.Cu" "F.Mask" "F.Paste")
			(net "P12V_OCP_TIMER_1")
		)
		(pad "2" smd circle
			(at 0.40005 0 90)
			(size 0 0)
			(layers "F.Cu" "F.Mask" "F.Paste")
			(net "GND")
		)
	)
)
